(kicad_pcb
	(version 20260206)
	(generator "pcbnew")
	(generator_version "10.0")
	(general
		(thickness 1.6)
		(legacy_teardrops no)
	)
	(paper "A4")
	(title_block
		(title "v1-pdb — T6M_PDB_D_0927_0900.brd")
		(comment 1 "Open CloudServer (Microsoft) / footprint 311 of 321 (J15), pads 1-46 of 46")
	)
	(layers
		(0 "F.Cu" signal "TOP")
		(4 "In1.Cu" signal "GND")
		(6 "In2.Cu" signal "IN1")
		(8 "In3.Cu" signal "VCC")
		(10 "In4.Cu" signal "VCC1")
		(12 "In5.Cu" signal "IN2")
		(14 "In6.Cu" signal "GND1")
		(2 "B.Cu" signal "BOTTOM")
		(9 "F.Adhes" user "F.Adhesive")
		(11 "B.Adhes" user "B.Adhesive")
		(13 "F.Paste" user "Package Geometry/Pastemask Top")
		(15 "B.Paste" user "Package Geometry/Pastemask Bottom")
		(5 "F.SilkS" user "Ref Des/Silkscreen Top")
		(7 "B.SilkS" user "Ref Des/Silkscreen Bottom")
		(1 "F.Mask" user "Board Geometry/Soldermask Top")
		(3 "B.Mask" user "Board Geometry/Soldermask Bottom")
		(17 "Dwgs.User" user "User.Drawings")
		(19 "Cmts.User" user "User.Comments")
		(21 "Eco1.User" user "User.Eco1")
		(23 "Eco2.User" user "User.Eco2")
		(25 "Edge.Cuts" user "Board Geometry/Outline")
		(27 "Margin" user)
		(31 "F.CrtYd" user "Package Geometry/Place Bound Top")
		(29 "B.CrtYd" user "Package Geometry/Place Bound Bottom")
		(35 "F.Fab" user "Ref Des/Assembly Top")
		(33 "B.Fab" user "Ref Des/Assembly Bottom")
	)
	(footprint ""
		(layer "B.Cu")
		(at 44.03979 -363.86008 90)
		(property "Reference" "J15"
			(at 6.521196 -4.437888 0)
			(unlocked yes)
			(layer "B.SilkS")
			(effects
				(font
					(size 0.7874 0.5842)
					(thickness 0.1524)
				)
				(justify left mirror)
			)
		)
		(property "Value" ""
			(at 0 0 90)
			(layer "B.Fab")
			(effects
				(font
					(size 1.27 1.27)
				)
				(justify mirror)
			)
		)
		(duplicate_pad_numbers_are_jumpers no)
		(pad "" np_thru_hole circle
			(at -1.35001 -2.54)
			(size 2.5146 2.5146)
			(drill 2.5146)
			(layers "*.Cu" "*.Mask")
			(clearance 0.381)
			(thermal_gap 0.381)
		)
		(pad "" np_thru_hole circle
			(at 0 50.8)
			(size 2.5146 2.5146)
			(drill 2.5146)
			(layers "*.Cu" "*.Mask")
			(clearance 0.381)
			(thermal_gap 0.381)
		)
		(pad "P1" thru_hole rect
			(at 0 0)
			(size 1.1684 1.1684)
			(drill 0.762)
			(layers "*.Cu" "*.Mask")
			(remove_unused_layers no)
			(net "GND")
			(clearance 0.0508)
			(padstack
				(mode front_inner_back)
				(layer "Inner"
					(shape circle)
					(size 1.1684 1.1684)
					(clearance 0.0508)
				)
				(layer "B.Cu"
					(shape rect)
					(size 1.1684 1.1684)
					(thermal_gap 0.0508)
					(clearance 0.0508)
				)
			)
		)
		(pad "P2" thru_hole circle
			(at 0 2.54)
			(size 1.1684 1.1684)
			(drill 0.762)
			(layers "*.Cu" "*.Mask")
			(remove_unused_layers no)
			(net "GND")
			(clearance 0.0508)
			(thermal_gap 0.0508)
		)
		(pad "P3" thru_hole circle
			(at 0 5.08)
			(size 1.1684 1.1684)
			(drill 0.762)
			(layers "*.Cu" "*.Mask")
			(remove_unused_layers no)
			(net "GND")
			(clearance 0.0508)
			(thermal_gap 0.0508)
		)
		(pad "P4" thru_hole circle
			(at 0 7.62)
			(size 1.1684 1.1684)
			(drill 0.762)
			(layers "*.Cu" "*.Mask")
			(remove_unused_layers no)
			(net "GND")
			(clearance 0.0508)
			(thermal_gap 0.0508)
		)
		(pad "P5" thru_hole circle
			(at 0 10.16)
			(size 1.1684 1.1684)
			(drill 0.762)
			(layers "*.Cu" "*.Mask")
			(remove_unused_layers no)
			(net "GND")
			(clearance 0.0508)
			(thermal_gap 0.0508)
		)
		(pad "P6" thru_hole circle
			(at 0 12.7)
			(size 1.1684 1.1684)
			(drill 0.762)
			(layers "*.Cu" "*.Mask")
			(remove_unused_layers no)
			(net "GND")
			(clearance 0.0508)
			(thermal_gap 0.0508)
		)
		(pad "P7" thru_hole circle
			(at 0 15.24)
			(size 1.1684 1.1684)
			(drill 0.762)
			(layers "*.Cu" "*.Mask")
			(remove_unused_layers no)
			(net "GND")
			(clearance 0.0508)
			(thermal_gap 0.0508)
		)
		(pad "P8" thru_hole circle
			(at 0 17.78)
			(size 1.1684 1.1684)
			(drill 0.762)
			(layers "*.Cu" "*.Mask")
			(remove_unused_layers no)
			(net "GND")
			(clearance 0.0508)
			(thermal_gap 0.0508)
		)
		(pad "P9" thru_hole circle
			(at 0 20.32)
			(size 1.1684 1.1684)
			(drill 0.762)
			(layers "*.Cu" "*.Mask")
			(remove_unused_layers no)
			(net "P12V")
			(clearance 0.0508)
			(thermal_gap 0.0508)
		)
		(pad "P10" thru_hole circle
			(at 0 22.86)
			(size 1.1684 1.1684)
			(drill 0.762)
			(layers "*.Cu" "*.Mask")
			(remove_unused_layers no)
			(net "P12V")
			(clearance 0.0508)
			(thermal_gap 0.0508)
		)
		(pad "P11" thru_hole circle
			(at 0 25.4)
			(size 1.1684 1.1684)
			(drill 0.762)
			(layers "*.Cu" "*.Mask")
			(remove_unused_layers no)
			(net "P12V")
			(clearance 0.0508)
			(thermal_gap 0.0508)
		)
		(pad "P12" thru_hole circle
			(at 0 27.94)
			(size 1.1684 1.1684)
			(drill 0.762)
			(layers "*.Cu" "*.Mask")
			(remove_unused_layers no)
			(net "P12V")
			(clearance 0.0508)
			(thermal_gap 0.0508)
		)
		(pad "P13" thru_hole circle
			(at 0 30.48)
			(size 1.1684 1.1684)
			(drill 0.762)
			(layers "*.Cu" "*.Mask")
			(remove_unused_layers no)
			(net "P12V")
			(clearance 0.0508)
			(thermal_gap 0.0508)
		)
		(pad "P14" thru_hole circle
			(at 0 33.02)
			(size 1.1684 1.1684)
			(drill 0.762)
			(layers "*.Cu" "*.Mask")
			(remove_unused_layers no)
			(net "P12V")
			(clearance 0.0508)
			(thermal_gap 0.0508)
		)
		(pad "P15" thru_hole circle
			(at 0 35.56)
			(size 1.1684 1.1684)
			(drill 0.762)
			(layers "*.Cu" "*.Mask")
			(remove_unused_layers no)
			(net "P12V")
			(clearance 0.0508)
			(thermal_gap 0.0508)
		)
		(pad "P16" thru_hole circle
			(at 0 38.1)
			(size 1.1684 1.1684)
			(drill 0.762)
			(layers "*.Cu" "*.Mask")
			(remove_unused_layers no)
			(net "P12V")
			(clearance 0.0508)
			(thermal_gap 0.0508)
		)
		(pad "P17" thru_hole circle
			(at -2.70002 38.1)
			(size 1.1684 1.1684)
			(drill 0.762)
			(layers "*.Cu" "*.Mask")
			(remove_unused_layers no)
			(net "P12V")
			(clearance 0.0508)
			(thermal_gap 0.0508)
		)
		(pad "P18" thru_hole circle
			(at -2.70002 35.56)
			(size 1.1684 1.1684)
			(drill 0.762)
			(layers "*.Cu" "*.Mask")
			(remove_unused_layers no)
			(net "P12V")
			(clearance 0.0508)
			(thermal_gap 0.0508)
		)
		(pad "P19" thru_hole circle
			(at -2.70002 33.02)
			(size 1.1684 1.1684)
			(drill 0.762)
			(layers "*.Cu" "*.Mask")
			(remove_unused_layers no)
			(net "P12V")
			(clearance 0.0508)
			(thermal_gap 0.0508)
		)
		(pad "P20" thru_hole circle
			(at -2.70002 30.48)
			(size 1.1684 1.1684)
			(drill 0.762)
			(layers "*.Cu" "*.Mask")
			(remove_unused_layers no)
			(net "P12V")
			(clearance 0.0508)
			(thermal_gap 0.0508)
		)
		(pad "P21" thru_hole circle
			(at -2.70002 27.94)
			(size 1.1684 1.1684)
			(drill 0.762)
			(layers "*.Cu" "*.Mask")
			(remove_unused_layers no)
			(net "P12V")
			(clearance 0.0508)
			(thermal_gap 0.0508)
		)
		(pad "P22" thru_hole circle
			(at -2.70002 25.4)
			(size 1.1684 1.1684)
			(drill 0.762)
			(layers "*.Cu" "*.Mask")
			(remove_unused_layers no)
			(net "P12V")
			(clearance 0.0508)
			(thermal_gap 0.0508)
		)
		(pad "P23" thru_hole circle
			(at -2.70002 22.86)
			(size 1.1684 1.1684)
			(drill 0.762)
			(layers "*.Cu" "*.Mask")
			(remove_unused_layers no)
			(net "P12V")
			(clearance 0.0508)
			(thermal_gap 0.0508)
		)
		(pad "P24" thru_hole circle
			(at -2.70002 20.32)
			(size 1.1684 1.1684)
			(drill 0.762)
			(layers "*.Cu" "*.Mask")
			(remove_unused_layers no)
			(net "P12V")
			(clearance 0.0508)
			(thermal_gap 0.0508)
		)
		(pad "P25" thru_hole circle
			(at -2.70002 17.78)
			(size 1.1684 1.1684)
			(drill 0.762)
			(layers "*.Cu" "*.Mask")
			(remove_unused_layers no)
			(net "GND")
			(clearance 0.0508)
			(thermal_gap 0.0508)
		)
		(pad "P26" thru_hole circle
			(at -2.70002 15.24)
			(size 1.1684 1.1684)
			(drill 0.762)
			(layers "*.Cu" "*.Mask")
			(remove_unused_layers no)
			(net "GND")
			(clearance 0.0508)
			(thermal_gap 0.0508)
		)
		(pad "P27" thru_hole circle
			(at -2.70002 12.7)
			(size 1.1684 1.1684)
			(drill 0.762)
			(layers "*.Cu" "*.Mask")
			(remove_unused_layers no)
			(net "GND")
			(clearance 0.0508)
			(thermal_gap 0.0508)
		)
		(pad "P28" thru_hole circle
			(at -2.70002 10.16)
			(size 1.1684 1.1684)
			(drill 0.762)
			(layers "*.Cu" "*.Mask")
			(remove_unused_layers no)
			(net "GND")
			(clearance 0.0508)
			(thermal_gap 0.0508)
		)
		(pad "P29" thru_hole circle
			(at -2.70002 7.62)
			(size 1.1684 1.1684)
			(drill 0.762)
			(layers "*.Cu" "*.Mask")
			(remove_unused_layers no)
			(net "GND")
			(clearance 0.0508)
			(thermal_gap 0.0508)
		)
		(pad "P30" thru_hole circle
			(at -2.70002 5.08)
			(size 1.1684 1.1684)
			(drill 0.762)
			(layers "*.Cu" "*.Mask")
			(remove_unused_layers no)
			(net "GND")
			(clearance 0.0508)
			(thermal_gap 0.0508)
		)
		(pad "P31" thru_hole circle
			(at -2.70002 2.54)
			(size 1.1684 1.1684)
			(drill 0.762)
			(layers "*.Cu" "*.Mask")
			(remove_unused_layers no)
			(net "GND")
			(clearance 0.0508)
			(thermal_gap 0.0508)
		)
		(pad "P32" thru_hole circle
			(at -2.70002 0)
			(size 1.1684 1.1684)
			(drill 0.762)
			(layers "*.Cu" "*.Mask")
			(remove_unused_layers no)
			(net "GND")
			(clearance 0.0508)
			(thermal_gap 0.0508)
		)
		(pad "S1" thru_hole circle
			(at 0.55499 41.60012)
			(size 1.1684 1.1684)
			(drill 0.762)
			(layers "*.Cu" "*.Mask")
			(remove_unused_layers no)
			(net "T9_BLAD1_TXD")
			(clearance 0.0508)
			(thermal_gap 0.0508)
		)
		(pad "S2" thru_hole circle
			(at -0.71501 42.87012)
			(size 1.1684 1.1684)
			(drill 0.762)
			(layers "*.Cu" "*.Mask")
			(remove_unused_layers no)
			(net "T9_BLAD1_RXD")
			(clearance 0.0508)
			(thermal_gap 0.0508)
		)
		(pad "S3" thru_hole circle
			(at 0.55499 44.14012)
			(size 1.1684 1.1684)
			(drill 0.762)
			(layers "*.Cu" "*.Mask")
			(remove_unused_layers no)
			(net "T9_BLAD1_EN")
			(clearance 0.0508)
			(thermal_gap 0.0508)
		)
		(pad "S4" thru_hole circle
			(at -0.71501 45.41012)
			(size 1.1684 1.1684)
			(drill 0.762)
			(layers "*.Cu" "*.Mask")
			(remove_unused_layers no)
			(net "T9_BLAD2_EN")
			(clearance 0.0508)
			(thermal_gap 0.0508)
		)
		(pad "S5" thru_hole circle
			(at 0.55499 46.68012)
			(size 1.1684 1.1684)
			(drill 0.762)
			(layers "*.Cu" "*.Mask")
			(remove_unused_layers no)
			(net "T9_BLAD2_TXD")
			(clearance 0.0508)
			(thermal_gap 0.0508)
		)
		(pad "S6" thru_hole circle
			(at -0.71501 47.95012)
			(size 1.1684 1.1684)
			(drill 0.762)
			(layers "*.Cu" "*.Mask")
			(remove_unused_layers no)
			(net "T9_BLAD2_RXD")
			(clearance 0.0508)
			(thermal_gap 0.0508)
		)
		(pad "S7" thru_hole circle
			(at -3.25501 47.95012)
			(size 1.1684 1.1684)
			(drill 0.762)
			(layers "*.Cu" "*.Mask")
			(remove_unused_layers no)
			(net "T9_BLAD4_RXD")
			(clearance 0.0508)
			(thermal_gap 0.0508)
		)
		(pad "S8" thru_hole circle
			(at -1.98501 46.68012)
			(size 1.1684 1.1684)
			(drill 0.762)
			(layers "*.Cu" "*.Mask")
			(remove_unused_layers no)
			(net "T9_BLAD4_TXD")
			(clearance 0.0508)
			(thermal_gap 0.0508)
		)
		(pad "S9" thru_hole circle
			(at -3.25501 45.41012)
			(size 1.1684 1.1684)
			(drill 0.762)
			(layers "*.Cu" "*.Mask")
			(remove_unused_layers no)
			(net "T9_BLAD4_EN")
			(clearance 0.0508)
			(thermal_gap 0.0508)
		)
		(pad "S10" thru_hole circle
			(at -1.98501 44.14012)
			(size 1.1684 1.1684)
			(drill 0.762)
			(layers "*.Cu" "*.Mask")
			(remove_unused_layers no)
			(net "T9_BLAD3_EN")
			(clearance 0.0508)
			(thermal_gap 0.0508)
		)
		(pad "S11" thru_hole circle
			(at -3.25501 42.87012)
			(size 1.1684 1.1684)
			(drill 0.762)
			(layers "*.Cu" "*.Mask")
			(remove_unused_layers no)
			(net "T9_BLAD3_RXD")
			(clearance 0.0508)
			(thermal_gap 0.0508)
		)
		(pad "S12" thru_hole circle
			(at -1.98501 41.60012)
			(size 1.1684 1.1684)
			(drill 0.762)
			(layers "*.Cu" "*.Mask")
			(remove_unused_layers no)
			(net "T9_BLAD3_TXD")
			(clearance 0.0508)
			(thermal_gap 0.0508)
		)
	)
)
